(kicad_pcb
	(version 20260206)
	(generator "pcbnew")
	(generator_version "10.0")
	(general
		(thickness 1.6)
		(legacy_teardrops no)
	)
	(paper "A4")
	(title_block
		(title "12092022_DA0F0TMDCD0_F0T_Management_Board_D_brd_V3_OCP.brd")
		(comment 1 "Grand Teton / footprints 968-973 of 1440")
	)
	(layers
		(0 "F.Cu" signal "TOP")
		(4 "In1.Cu" signal "GND")
		(6 "In2.Cu" signal "IN1")
		(8 "In3.Cu" signal "GND1")
		(10 "In4.Cu" signal "IN2")
		(12 "In5.Cu" signal "VCC")
		(14 "In6.Cu" signal "VCC1")
		(16 "In7.Cu" signal "IN3")
		(18 "In8.Cu" signal "GND2")
		(20 "In9.Cu" signal "IN4")
		(22 "In10.Cu" signal "GND3")
		(2 "B.Cu" signal "BOTTOM")
		(9 "F.Adhes" user "F.Adhesive")
		(11 "B.Adhes" user "B.Adhesive")
		(13 "F.Paste" user "Package Geometry/Pastemask Top")
		(15 "B.Paste" user "Package Geometry/Pastemask Bottom")
		(5 "F.SilkS" user "Ref Des/Silkscreen Top")
		(7 "B.SilkS" user "Ref Des/Silkscreen Bottom")
		(1 "F.Mask" user "Board Geometry/Soldermask Top")
		(3 "B.Mask" user "Board Geometry/Soldermask Bottom")
		(17 "Dwgs.User" user "User.Drawings")
		(19 "Cmts.User" user "User.Comments")
		(21 "Eco1.User" user "User.Eco1")
		(23 "Eco2.User" user "User.Eco2")
		(25 "Edge.Cuts" user "Board Geometry/Outline")
		(27 "Margin" user)
		(31 "F.CrtYd" user "Package Geometry/Place Bound Top")
		(29 "B.CrtYd" user "Package Geometry/Place Bound Bottom")
		(35 "F.Fab" user "Ref Des/Assembly Top")
		(33 "B.Fab" user "Ref Des/Assembly Bottom")
	)
	(footprint ""
		(layer "B.Cu")
		(at 13.335 -106.426 90)
		(property "Reference" "R898"
			(at 0 0 90)
			(layer "B.SilkS")
			(hide yes)
			(effects
				(font
					(size 1.27 1.27)
				)
				(justify mirror)
			)
		)
		(property "Value" ""
			(at 0 0 90)
			(layer "B.Fab")
			(effects
				(font
					(size 1.27 1.27)
				)
				(justify mirror)
			)
		)
		(duplicate_pad_numbers_are_jumpers no)
		(fp_line
			(start 0.7874 -0.4064)
			(end -0.7874 -0.4064)
			(stroke
				(width 0.1524)
				(type default)
			)
			(layer "B.SilkS")
		)
		(fp_line
			(start -0.7874 -0.4064)
			(end -0.7874 0.4064)
			(stroke
				(width 0.1524)
				(type default)
			)
			(layer "B.SilkS")
		)
		(fp_line
			(start 0.7874 0.4064)
			(end 0.7874 -0.4064)
			(stroke
				(width 0.1524)
				(type default)
			)
			(layer "B.SilkS")
		)
		(fp_line
			(start -0.7874 0.4064)
			(end 0.7874 0.4064)
			(stroke
				(width 0.1524)
				(type default)
			)
			(layer "B.SilkS")
		)
		(fp_line
			(start 0.67945 -0.305054)
			(end 0.12065 -0.305054)
			(stroke
				(width 0.1)
				(type default)
			)
			(layer "B.Fab")
		)
		(fp_line
			(start 0.12065 -0.305054)
			(end 0.12065 -0.2794)
			(stroke
				(width 0.1)
				(type default)
			)
			(layer "B.Fab")
		)
		(fp_line
			(start -0.12065 -0.3048)
			(end -0.67945 -0.3048)
			(stroke
				(width 0.1)
				(type default)
			)
			(layer "B.Fab")
		)
		(fp_line
			(start -0.67945 -0.3048)
			(end -0.67945 0.3048)
			(stroke
				(width 0.1)
				(type default)
			)
			(layer "B.Fab")
		)
		(fp_line
			(start 0.12065 -0.2794)
			(end -0.12065 -0.2794)
			(stroke
				(width 0.1)
				(type default)
			)
			(layer "B.Fab")
		)
		(fp_line
			(start -0.12065 -0.2794)
			(end -0.12065 -0.3048)
			(stroke
				(width 0.1)
				(type default)
			)
			(layer "B.Fab")
		)
		(fp_line
			(start 0.12065 0.2794)
			(end 0.12065 0.3048)
			(stroke
				(width 0.1)
				(type default)
			)
			(layer "B.Fab")
		)
		(fp_line
			(start -0.120396 0.2794)
			(end 0.12065 0.2794)
			(stroke
				(width 0.1)
				(type default)
			)
			(layer "B.Fab")
		)
		(fp_line
			(start 0.67945 0.3048)
			(end 0.67945 -0.305054)
			(stroke
				(width 0.1)
				(type default)
			)
			(layer "B.Fab")
		)
		(fp_line
			(start 0.12065 0.3048)
			(end 0.67945 0.3048)
			(stroke
				(width 0.1)
				(type default)
			)
			(layer "B.Fab")
		)
		(fp_line
			(start -0.120396 0.3048)
			(end -0.120396 0.2794)
			(stroke
				(width 0.1)
				(type default)
			)
			(layer "B.Fab")
		)
		(fp_line
			(start -0.67945 0.3048)
			(end -0.120396 0.3048)
			(stroke
				(width 0.1)
				(type default)
			)
			(layer "B.Fab")
		)
		(pad "1" smd circle
			(at 0.40005 0 270)
			(size 0 0)
			(layers "B.Cu" "B.Mask" "B.Paste")
			(net "FM_UARTSW_LSB_R_N")
		)
		(pad "2" smd circle
			(at -0.40005 0 270)
			(size 0 0)
			(layers "B.Cu" "B.Mask" "B.Paste")
			(net "FM_UARTSW_LSB_N")
		)
	)
	(footprint ""
		(layer "B.Cu")
		(at 37.4015 -99.568 180)
		(property "Reference" "R728"
			(at 0 0 0)
			(layer "B.SilkS")
			(hide yes)
			(effects
				(font
					(size 1.27 1.27)
				)
				(justify mirror)
			)
		)
		(property "Value" ""
			(at 0 0 0)
			(layer "B.Fab")
			(effects
				(font
					(size 1.27 1.27)
				)
				(justify mirror)
			)
		)
		(duplicate_pad_numbers_are_jumpers no)
		(fp_line
			(start 0.7874 0.4064)
			(end 0.7874 -0.4064)
			(stroke
				(width 0.1524)
				(type default)
			)
			(layer "B.SilkS")
		)
		(fp_line
			(start 0.7874 -0.4064)
			(end -0.7874 -0.4064)
			(stroke
				(width 0.1524)
				(type default)
			)
			(layer "B.SilkS")
		)
		(fp_line
			(start -0.7874 0.4064)
			(end 0.7874 0.4064)
			(stroke
				(width 0.1524)
				(type default)
			)
			(layer "B.SilkS")
		)
		(fp_line
			(start -0.7874 -0.4064)
			(end -0.7874 0.4064)
			(stroke
				(width 0.1524)
				(type default)
			)
			(layer "B.SilkS")
		)
		(fp_line
			(start 0.67945 0.3048)
			(end 0.67945 -0.305054)
			(stroke
				(width 0.1)
				(type default)
			)
			(layer "B.Fab")
		)
		(fp_line
			(start 0.67945 -0.305054)
			(end 0.12065 -0.305054)
			(stroke
				(width 0.1)
				(type default)
			)
			(layer "B.Fab")
		)
		(fp_line
			(start 0.12065 0.3048)
			(end 0.67945 0.3048)
			(stroke
				(width 0.1)
				(type default)
			)
			(layer "B.Fab")
		)
		(fp_line
			(start 0.12065 0.2794)
			(end 0.12065 0.3048)
			(stroke
				(width 0.1)
				(type default)
			)
			(layer "B.Fab")
		)
		(fp_line
			(start 0.12065 -0.2794)
			(end -0.12065 -0.2794)
			(stroke
				(width 0.1)
				(type default)
			)
			(layer "B.Fab")
		)
		(fp_line
			(start 0.12065 -0.305054)
			(end 0.12065 -0.2794)
			(stroke
				(width 0.1)
				(type default)
			)
			(layer "B.Fab")
		)
		(fp_line
			(start -0.120396 0.3048)
			(end -0.120396 0.2794)
			(stroke
				(width 0.1)
				(type default)
			)
			(layer "B.Fab")
		)
		(fp_line
			(start -0.120396 0.2794)
			(end 0.12065 0.2794)
			(stroke
				(width 0.1)
				(type default)
			)
			(layer "B.Fab")
		)
		(fp_line
			(start -0.12065 -0.2794)
			(end -0.12065 -0.3048)
			(stroke
				(width 0.1)
				(type default)
			)
			(layer "B.Fab")
		)
		(fp_line
			(start -0.12065 -0.3048)
			(end -0.67945 -0.3048)
			(stroke
				(width 0.1)
				(type default)
			)
			(layer "B.Fab")
		)
		(fp_line
			(start -0.67945 0.3048)
			(end -0.120396 0.3048)
			(stroke
				(width 0.1)
				(type default)
			)
			(layer "B.Fab")
		)
		(fp_line
			(start -0.67945 -0.3048)
			(end -0.67945 0.3048)
			(stroke
				(width 0.1)
				(type default)
			)
			(layer "B.Fab")
		)
		(pad "1" smd circle
			(at 0.40005 0)
			(size 0 0)
			(layers "B.Cu" "B.Mask" "B.Paste")
			(net "SPI_BMC_BIOS_CS0_N")
		)
		(pad "2" smd circle
			(at -0.40005 0)
			(size 0 0)
			(layers "B.Cu" "B.Mask" "B.Paste")
			(net "SPI_BMC_BIOS_SOURCE_CS0_N")
		)
	)
	(footprint ""
		(layer "B.Cu")
		(at 57.906666 -74.66584 180)
		(property "Reference" "R787"
			(at 0 0 0)
			(layer "B.SilkS")
			(hide yes)
			(effects
				(font
					(size 1.27 1.27)
				)
				(justify mirror)
			)
		)
		(property "Value" ""
			(at 0 0 0)
			(layer "B.Fab")
			(effects
				(font
					(size 1.27 1.27)
				)
				(justify mirror)
			)
		)
		(duplicate_pad_numbers_are_jumpers no)
		(fp_line
			(start 0.7874 0.4064)
			(end 0.7874 -0.4064)
			(stroke
				(width 0.1524)
				(type default)
			)
			(layer "B.SilkS")
		)
		(fp_line
			(start 0.7874 -0.4064)
			(end -0.7874 -0.4064)
			(stroke
				(width 0.1524)
				(type default)
			)
			(layer "B.SilkS")
		)
		(fp_line
			(start -0.7874 0.4064)
			(end 0.7874 0.4064)
			(stroke
				(width 0.1524)
				(type default)
			)
			(layer "B.SilkS")
		)
		(fp_line
			(start -0.7874 -0.4064)
			(end -0.7874 0.4064)
			(stroke
				(width 0.1524)
				(type default)
			)
			(layer "B.SilkS")
		)
		(fp_line
			(start 0.67945 0.3048)
			(end 0.67945 -0.305054)
			(stroke
				(width 0.1)
				(type default)
			)
			(layer "B.Fab")
		)
		(fp_line
			(start 0.67945 -0.305054)
			(end 0.12065 -0.305054)
			(stroke
				(width 0.1)
				(type default)
			)
			(layer "B.Fab")
		)
		(fp_line
			(start 0.12065 0.3048)
			(end 0.67945 0.3048)
			(stroke
				(width 0.1)
				(type default)
			)
			(layer "B.Fab")
		)
		(fp_line
			(start 0.12065 0.2794)
			(end 0.12065 0.3048)
			(stroke
				(width 0.1)
				(type default)
			)
			(layer "B.Fab")
		)
		(fp_line
			(start 0.12065 -0.2794)
			(end -0.12065 -0.2794)
			(stroke
				(width 0.1)
				(type default)
			)
			(layer "B.Fab")
		)
		(fp_line
			(start 0.12065 -0.305054)
			(end 0.12065 -0.2794)
			(stroke
				(width 0.1)
				(type default)
			)
			(layer "B.Fab")
		)
		(fp_line
			(start -0.120396 0.3048)
			(end -0.120396 0.2794)
			(stroke
				(width 0.1)
				(type default)
			)
			(layer "B.Fab")
		)
		(fp_line
			(start -0.120396 0.2794)
			(end 0.12065 0.2794)
			(stroke
				(width 0.1)
				(type default)
			)
			(layer "B.Fab")
		)
		(fp_line
			(start -0.12065 -0.2794)
			(end -0.12065 -0.3048)
			(stroke
				(width 0.1)
				(type default)
			)
			(layer "B.Fab")
		)
		(fp_line
			(start -0.12065 -0.3048)
			(end -0.67945 -0.3048)
			(stroke
				(width 0.1)
				(type default)
			)
			(layer "B.Fab")
		)
		(fp_line
			(start -0.67945 0.3048)
			(end -0.120396 0.3048)
			(stroke
				(width 0.1)
				(type default)
			)
			(layer "B.Fab")
		)
		(fp_line
			(start -0.67945 -0.3048)
			(end -0.67945 0.3048)
			(stroke
				(width 0.1)
				(type default)
			)
			(layer "B.Fab")
		)
		(pad "1" smd circle
			(at 0.40005 0)
			(size 0 0)
			(layers "B.Cu" "B.Mask" "B.Paste")
			(net "P5V_AUX")
		)
		(pad "2" smd circle
			(at -0.40005 0)
			(size 0 0)
			(layers "B.Cu" "B.Mask" "B.Paste")
			(net "P5V_SENSOR")
		)
	)
	(footprint ""
		(layer "B.Cu")
		(at 50.858674 -70.800722 180)
		(property "Reference" "R794"
			(at 0 0 0)
			(layer "B.SilkS")
			(hide yes)
			(effects
				(font
					(size 1.27 1.27)
				)
				(justify mirror)
			)
		)
		(property "Value" ""
			(at 0 0 0)
			(layer "B.Fab")
			(effects
				(font
					(size 1.27 1.27)
				)
				(justify mirror)
			)
		)
		(duplicate_pad_numbers_are_jumpers no)
		(fp_line
			(start 0.7874 0.4064)
			(end 0.7874 -0.4064)
			(stroke
				(width 0.1524)
				(type default)
			)
			(layer "B.SilkS")
		)
		(fp_line
			(start 0.7874 -0.4064)
			(end -0.7874 -0.4064)
			(stroke
				(width 0.1524)
				(type default)
			)
			(layer "B.SilkS")
		)
		(fp_line
			(start -0.7874 0.4064)
			(end 0.7874 0.4064)
			(stroke
				(width 0.1524)
				(type default)
			)
			(layer "B.SilkS")
		)
		(fp_line
			(start -0.7874 -0.4064)
			(end -0.7874 0.4064)
			(stroke
				(width 0.1524)
				(type default)
			)
			(layer "B.SilkS")
		)
		(fp_line
			(start 0.67945 0.3048)
			(end 0.67945 -0.305054)
			(stroke
				(width 0.1)
				(type default)
			)
			(layer "B.Fab")
		)
		(fp_line
			(start 0.67945 -0.305054)
			(end 0.12065 -0.305054)
			(stroke
				(width 0.1)
				(type default)
			)
			(layer "B.Fab")
		)
		(fp_line
			(start 0.12065 0.3048)
			(end 0.67945 0.3048)
			(stroke
				(width 0.1)
				(type default)
			)
			(layer "B.Fab")
		)
		(fp_line
			(start 0.12065 0.2794)
			(end 0.12065 0.3048)
			(stroke
				(width 0.1)
				(type default)
			)
			(layer "B.Fab")
		)
		(fp_line
			(start 0.12065 -0.2794)
			(end -0.12065 -0.2794)
			(stroke
				(width 0.1)
				(type default)
			)
			(layer "B.Fab")
		)
		(fp_line
			(start 0.12065 -0.305054)
			(end 0.12065 -0.2794)
			(stroke
				(width 0.1)
				(type default)
			)
			(layer "B.Fab")
		)
		(fp_line
			(start -0.120396 0.3048)
			(end -0.120396 0.2794)
			(stroke
				(width 0.1)
				(type default)
			)
			(layer "B.Fab")
		)
		(fp_line
			(start -0.120396 0.2794)
			(end 0.12065 0.2794)
			(stroke
				(width 0.1)
				(type default)
			)
			(layer "B.Fab")
		)
		(fp_line
			(start -0.12065 -0.2794)
			(end -0.12065 -0.3048)
			(stroke
				(width 0.1)
				(type default)
			)
			(layer "B.Fab")
		)
		(fp_line
			(start -0.12065 -0.3048)
			(end -0.67945 -0.3048)
			(stroke
				(width 0.1)
				(type default)
			)
			(layer "B.Fab")
		)
		(fp_line
			(start -0.67945 0.3048)
			(end -0.120396 0.3048)
			(stroke
				(width 0.1)
				(type default)
			)
			(layer "B.Fab")
		)
		(fp_line
			(start -0.67945 -0.3048)
			(end -0.67945 0.3048)
			(stroke
				(width 0.1)
				(type default)
			)
			(layer "B.Fab")
		)
		(pad "1" smd circle
			(at 0.40005 0)
			(size 0 0)
			(layers "B.Cu" "B.Mask" "B.Paste")
			(net "P1V8_SENSOR")
		)
		(pad "2" smd circle
			(at -0.40005 0)
			(size 0 0)
			(layers "B.Cu" "B.Mask" "B.Paste")
			(net "GND")
		)
	)
	(footprint ""
		(layer "B.Cu")
		(at 60.85586 -30.867604 -90)
		(property "Reference" "R427"
			(at 0 0 90)
			(layer "B.SilkS")
			(hide yes)
			(effects
				(font
					(size 1.27 1.27)
				)
				(justify mirror)
			)
		)
		(property "Value" ""
			(at 0 0 90)
			(layer "B.Fab")
			(effects
				(font
					(size 1.27 1.27)
				)
				(justify mirror)
			)
		)
		(duplicate_pad_numbers_are_jumpers no)
		(fp_line
			(start -0.7874 0.4064)
			(end 0.7874 0.4064)
			(stroke
				(width 0.1524)
				(type default)
			)
			(layer "B.SilkS")
		)
		(fp_line
			(start 0.7874 0.4064)
			(end 0.7874 -0.4064)
			(stroke
				(width 0.1524)
				(type default)
			)
			(layer "B.SilkS")
		)
		(fp_line
			(start -0.7874 -0.4064)
			(end -0.7874 0.4064)
			(stroke
				(width 0.1524)
				(type default)
			)
			(layer "B.SilkS")
		)
		(fp_line
			(start 0.7874 -0.4064)
			(end -0.7874 -0.4064)
			(stroke
				(width 0.1524)
				(type default)
			)
			(layer "B.SilkS")
		)
		(fp_line
			(start -0.67945 0.3048)
			(end -0.120396 0.3048)
			(stroke
				(width 0.1)
				(type default)
			)
			(layer "B.Fab")
		)
		(fp_line
			(start -0.120396 0.3048)
			(end -0.120396 0.2794)
			(stroke
				(width 0.1)
				(type default)
			)
			(layer "B.Fab")
		)
		(fp_line
			(start 0.12065 0.3048)
			(end 0.67945 0.3048)
			(stroke
				(width 0.1)
				(type default)
			)
			(layer "B.Fab")
		)
		(fp_line
			(start 0.67945 0.3048)
			(end 0.67945 -0.305054)
			(stroke
				(width 0.1)
				(type default)
			)
			(layer "B.Fab")
		)
		(fp_line
			(start -0.120396 0.2794)
			(end 0.12065 0.2794)
			(stroke
				(width 0.1)
				(type default)
			)
			(layer "B.Fab")
		)
		(fp_line
			(start 0.12065 0.2794)
			(end 0.12065 0.3048)
			(stroke
				(width 0.1)
				(type default)
			)
			(layer "B.Fab")
		)
		(fp_line
			(start -0.12065 -0.2794)
			(end -0.12065 -0.3048)
			(stroke
				(width 0.1)
				(type default)
			)
			(layer "B.Fab")
		)
		(fp_line
			(start 0.12065 -0.2794)
			(end -0.12065 -0.2794)
			(stroke
				(width 0.1)
				(type default)
			)
			(layer "B.Fab")
		)
		(fp_line
			(start -0.67945 -0.3048)
			(end -0.67945 0.3048)
			(stroke
				(width 0.1)
				(type default)
			)
			(layer "B.Fab")
		)
		(fp_line
			(start -0.12065 -0.3048)
			(end -0.67945 -0.3048)
			(stroke
				(width 0.1)
				(type default)
			)
			(layer "B.Fab")
		)
		(fp_line
			(start 0.12065 -0.305054)
			(end 0.12065 -0.2794)
			(stroke
				(width 0.1)
				(type default)
			)
			(layer "B.Fab")
		)
		(fp_line
			(start 0.67945 -0.305054)
			(end 0.12065 -0.305054)
			(stroke
				(width 0.1)
				(type default)
			)
			(layer "B.Fab")
		)
		(pad "1" smd circle
			(at 0.40005 0 90)
			(size 0 0)
			(layers "B.Cu" "B.Mask" "B.Paste")
			(net "UART_BMC_1_RXD_R")
		)
		(pad "2" smd circle
			(at -0.40005 0 90)
			(size 0 0)
			(layers "B.Cu" "B.Mask" "B.Paste")
			(net "UART_BMC_1_RXD")
		)
	)
	(footprint ""
		(layer "B.Cu")
		(at 53.006498 -49.3903)
		(property "Reference" "C117"
			(at 0 0 0)
			(layer "B.SilkS")
			(hide yes)
			(effects
				(font
					(size 1.27 1.27)
				)
				(justify mirror)
			)
		)
		(property "Value" ""
			(at 0 0 0)
			(layer "B.Fab")
			(effects
				(font
					(size 1.27 1.27)
				)
				(justify mirror)
			)
		)
		(duplicate_pad_numbers_are_jumpers no)
		(fp_line
			(start -0.7874 -0.4064)
			(end -0.7874 0.4064)
			(stroke
				(width 0.1524)
				(type default)
			)
			(layer "B.SilkS")
		)
		(fp_line
			(start -0.7874 0.4064)
			(end 0.7874 0.4064)
			(stroke
				(width 0.1524)
				(type default)
			)
			(layer "B.SilkS")
		)
		(fp_line
			(start 0.7874 -0.4064)
			(end -0.7874 -0.4064)
			(stroke
				(width 0.1524)
				(type default)
			)
			(layer "B.SilkS")
		)
		(fp_line
			(start 0.7874 0.4064)
			(end 0.7874 -0.4064)
			(stroke
				(width 0.1524)
				(type default)
			)
			(layer "B.SilkS")
		)
		(fp_line
			(start -0.67945 -0.3048)
			(end -0.67945 0.3048)
			(stroke
				(width 0.1)
				(type default)
			)
			(layer "B.Fab")
		)
		(fp_line
			(start -0.67945 0.3048)
			(end -0.120396 0.3048)
			(stroke
				(width 0.1)
				(type default)
			)
			(layer "B.Fab")
		)
		(fp_line
			(start -0.12065 -0.3048)
			(end -0.67945 -0.3048)
			(stroke
				(width 0.1)
				(type default)
			)
			(layer "B.Fab")
		)
		(fp_line
			(start -0.12065 -0.2794)
			(end -0.12065 -0.3048)
			(stroke
				(width 0.1)
				(type default)
			)
			(layer "B.Fab")
		)
		(fp_line
			(start -0.120396 0.2794)
			(end 0.12065 0.2794)
			(stroke
				(width 0.1)
				(type default)
			)
			(layer "B.Fab")
		)
		(fp_line
			(start -0.120396 0.3048)
			(end -0.120396 0.2794)
			(stroke
				(width 0.1)
				(type default)
			)
			(layer "B.Fab")
		)
		(fp_line
			(start 0.12065 -0.305054)
			(end 0.12065 -0.2794)
			(stroke
				(width 0.1)
				(type default)
			)
			(layer "B.Fab")
		)
		(fp_line
			(start 0.12065 -0.2794)
			(end -0.12065 -0.2794)
			(stroke
				(width 0.1)
				(type default)
			)
			(layer "B.Fab")
		)
		(fp_line
			(start 0.12065 0.2794)
			(end 0.12065 0.3048)
			(stroke
				(width 0.1)
				(type default)
			)
			(layer "B.Fab")
		)
		(fp_line
			(start 0.12065 0.3048)
			(end 0.67945 0.3048)
			(stroke
				(width 0.1)
				(type default)
			)
			(layer "B.Fab")
		)
		(fp_line
			(start 0.67945 -0.305054)
			(end 0.12065 -0.305054)
			(stroke
				(width 0.1)
				(type default)
			)
			(layer "B.Fab")
		)
		(fp_line
			(start 0.67945 0.3048)
			(end 0.67945 -0.305054)
			(stroke
				(width 0.1)
				(type default)
			)
			(layer "B.Fab")
		)
		(pad "1" smd circle
			(at 0.40005 0 180)
			(size 0 0)
			(layers "B.Cu" "B.Mask" "B.Paste")
			(net "P1V2_AUX")
		)
		(pad "2" smd circle
			(at -0.40005 0 180)
			(size 0 0)
			(layers "B.Cu" "B.Mask" "B.Paste")
			(net "GND")
		)
	)
)
